(kicad_pcb
	(version 20260206)
	(generator "pcbnew")
	(generator_version "10.0")
	(general
		(thickness 1.6)
		(legacy_teardrops no)
	)
	(paper "A4")
	(title_block
		(title "Bryce Canyon_F.DPB_16315-1-OCP.brd")
		(comment 1 "Bryce Canyon / footprints 551-558 of 2223")
	)
	(layers
		(0 "F.Cu" signal "TOP")
		(4 "In1.Cu" signal "L2GND")
		(6 "In2.Cu" signal "L3")
		(8 "In3.Cu" signal "L4GND")
		(10 "In4.Cu" signal "L5")
		(12 "In5.Cu" signal "L6VCC")
		(14 "In6.Cu" signal "L7VCC")
		(16 "In7.Cu" signal "L8")
		(18 "In8.Cu" signal "L9GND")
		(20 "In9.Cu" signal "L10")
		(22 "In10.Cu" signal "L11GND")
		(2 "B.Cu" signal "BOTTOM")
		(9 "F.Adhes" user "F.Adhesive")
		(11 "B.Adhes" user "B.Adhesive")
		(13 "F.Paste" user "Package Geometry/Pastemask Top")
		(15 "B.Paste" user "Package Geometry/Pastemask Bottom")
		(5 "F.SilkS" user "Ref Des/Silkscreen Top")
		(7 "B.SilkS" user "Ref Des/Silkscreen Bottom")
		(1 "F.Mask" user "Board Geometry/Soldermask Top")
		(3 "B.Mask" user "Board Geometry/Soldermask Bottom")
		(17 "Dwgs.User" user "User.Drawings")
		(19 "Cmts.User" user "User.Comments")
		(21 "Eco1.User" user "User.Eco1")
		(23 "Eco2.User" user "User.Eco2")
		(25 "Edge.Cuts" user "Board Geometry/Outline")
		(27 "Margin" user)
		(31 "F.CrtYd" user "Package Geometry/Place Bound Top")
		(29 "B.CrtYd" user "Package Geometry/Place Bound Bottom")
		(35 "F.Fab" user "Ref Des/Assembly Top")
		(33 "B.Fab" user "Ref Des/Assembly Bottom")
	)
	(footprint ""
		(layer "F.Cu")
		(at 315.016388 -242.745768 180)
		(property "Reference" "Q269"
			(at 0 0 180)
			(layer "F.SilkS")
			(hide yes)
			(effects
				(font
					(size 1.27 1.27)
				)
			)
		)
		(property "Value" "SSM3K324R-GP"
			(at 0.127 -8.9662 180)
			(unlocked yes)
			(layer "F.Fab")
			(hide yes)
			(effects
				(font
					(size 1.016 1.016)
					(thickness 0.1524)
				)
			)
		)
		(property "Device Type" "SOT23DGS2D4H35"
			(at 0.127 -10.4902 180)
			(unlocked yes)
			(layer "F.Fab")
			(hide yes)
			(effects
				(font
					(size 1.016 1.016)
					(thickness 0.1524)
				)
			)
		)
		(duplicate_pad_numbers_are_jumpers no)
		(fp_line
			(start 1.651 1.778)
			(end 1.651 -1.778)
			(stroke
				(width 0.1524)
				(type default)
			)
			(layer "F.SilkS")
		)
		(fp_line
			(start 1.651 -1.778)
			(end -1.651 -1.778)
			(stroke
				(width 0.1524)
				(type default)
			)
			(layer "F.SilkS")
		)
		(fp_line
			(start -1.651 1.778)
			(end 1.651 1.778)
			(stroke
				(width 0.1524)
				(type default)
			)
			(layer "F.SilkS")
		)
		(fp_line
			(start -1.651 -1.778)
			(end -1.651 1.778)
			(stroke
				(width 0.1524)
				(type default)
			)
			(layer "F.SilkS")
		)
		(fp_poly
			(pts
				(xy -1.778 1.8796) (xy -1.778 -1.8796) (xy 1.778 -1.8796) (xy 1.778 1.8796)
			)
			(stroke
				(width 0)
				(type default)
			)
			(fill no)
			(layer "F.CrtYd")
		)
		(fp_poly
			(pts
				(xy -1.778 1.8796) (xy -1.778 -1.8796) (xy 1.778 -1.8796) (xy 1.778 1.8796)
			)
			(stroke
				(width 0)
				(type default)
			)
			(fill no)
			(layer "F.Fab")
		)
		(pad "D" smd custom
			(at 0 -0.9525 180)
			(size 0.1905 0.1905)
			(layers "F.Cu" "F.Mask" "F.Paste")
			(net "DRV_ACT_6_N")
			(options
				(clearance outline)
				(anchor circle)
			)
			(primitives
				(gr_poly
					(pts
						(arc
							(start -0.1778 0.5715)
							(mid -0.321484 0.511984)
							(end -0.381 0.3683)
						)
						(arc
							(start -0.381 -0.3683)
							(mid -0.321484 -0.511984)
							(end -0.1778 -0.5715)
						)
						(arc
							(start 0.1778 -0.5715)
							(mid 0.321484 -0.511984)
							(end 0.381 -0.3683)
						)
						(arc
							(start 0.381 0.3683)
							(mid 0.321484 0.511984)
							(end 0.1778 0.5715)
						)
					)
					(width 0)
					(fill yes)
				)
			)
		)
		(pad "G" smd custom
			(at -0.98425 0.9525 180)
			(size 0.1905 0.1905)
			(layers "F.Cu" "F.Mask" "F.Paste")
			(net "DRIVE_A_6_ACT")
			(options
				(clearance outline)
				(anchor circle)
			)
			(primitives
				(gr_poly
					(pts
						(arc
							(start -0.1778 0.5715)
							(mid -0.321484 0.511984)
							(end -0.381 0.3683)
						)
						(arc
							(start -0.381 -0.3683)
							(mid -0.321484 -0.511984)
							(end -0.1778 -0.5715)
						)
						(arc
							(start 0.1778 -0.5715)
							(mid 0.321484 -0.511984)
							(end 0.381 -0.3683)
						)
						(arc
							(start 0.381 0.3683)
							(mid 0.321484 0.511984)
							(end 0.1778 0.5715)
						)
					)
					(width 0)
					(fill yes)
				)
			)
		)
		(pad "S" smd custom
			(at 0.98425 0.9525 180)
			(size 0.1905 0.1905)
			(layers "F.Cu" "F.Mask" "F.Paste")
			(net "GND")
			(options
				(clearance outline)
				(anchor circle)
			)
			(primitives
				(gr_poly
					(pts
						(arc
							(start -0.1778 0.5715)
							(mid -0.321484 0.511984)
							(end -0.381 0.3683)
						)
						(arc
							(start -0.381 -0.3683)
							(mid -0.321484 -0.511984)
							(end -0.1778 -0.5715)
						)
						(arc
							(start 0.1778 -0.5715)
							(mid 0.321484 -0.511984)
							(end 0.381 -0.3683)
						)
						(arc
							(start 0.381 0.3683)
							(mid 0.321484 0.511984)
							(end 0.1778 0.5715)
						)
					)
					(width 0)
					(fill yes)
				)
			)
		)
	)
	(footprint ""
		(layer "F.Cu")
		(at 286.7406 -272.3134 180)
		(property "Reference" "R121"
			(at 0 0 180)
			(layer "F.SilkS")
			(hide yes)
			(effects
				(font
					(size 1.27 1.27)
				)
			)
		)
		(property "Value" "4K7R2F-GP"
			(at 0.064008 -3.993896 180)
			(unlocked yes)
			(layer "F.Fab")
			(hide yes)
			(effects
				(font
					(size 1.016 1.016)
					(thickness 0.1524)
				)
			)
		)
		(property "Device Type" "R402H16"
			(at 0.064008 -5.517896 180)
			(unlocked yes)
			(layer "F.Fab")
			(hide yes)
			(effects
				(font
					(size 1.016 1.016)
					(thickness 0.1524)
				)
			)
		)
		(duplicate_pad_numbers_are_jumpers no)
		(fp_line
			(start 0.508 -0.9398)
			(end -0.508 -0.9398)
			(stroke
				(width 0.1524)
				(type default)
			)
			(layer "F.SilkS")
		)
		(fp_line
			(start -0.508 -0.9398)
			(end -0.508 0.9398)
			(stroke
				(width 0.1524)
				(type default)
			)
			(layer "F.SilkS")
		)
		(fp_rect
			(start -0.508 0.9398)
			(end 0.508 -0.9398)
			(stroke
				(width 0)
				(type default)
			)
			(fill no)
			(layer "F.CrtYd")
		)
		(fp_rect
			(start -0.508 0.9398)
			(end 0.508 -0.9398)
			(stroke
				(width 0)
				(type default)
			)
			(fill no)
			(layer "F.Fab")
		)
		(pad "1" smd custom
			(at 0 -0.4445 180)
			(size 0.1397 0.1397)
			(layers "F.Cu" "F.Mask" "F.Paste")
			(net "P3V3_STBY_A")
			(options
				(clearance outline)
				(anchor circle)
			)
			(primitives
				(gr_poly
					(pts
						(arc
							(start -0.1778 -0.2794)
							(mid -0.249642 -0.249642)
							(end -0.2794 -0.1778)
						)
						(arc
							(start -0.2794 0.1778)
							(mid -0.249642 0.249642)
							(end -0.1778 0.2794)
						)
						(arc
							(start 0.1778 0.2794)
							(mid 0.249642 0.249642)
							(end 0.2794 0.1778)
						)
						(arc
							(start 0.2794 -0.1778)
							(mid 0.249642 -0.249642)
							(end 0.1778 -0.2794)
						)
					)
					(width 0)
					(fill yes)
				)
			)
		)
		(pad "2" smd custom
			(at 0 0.4445 180)
			(size 0.1397 0.1397)
			(layers "F.Cu" "F.Mask" "F.Paste")
			(net "IO_EXP2_HDD_FAULT_A2")
			(options
				(clearance outline)
				(anchor circle)
			)
			(primitives
				(gr_poly
					(pts
						(arc
							(start -0.1778 -0.2794)
							(mid -0.249642 -0.249642)
							(end -0.2794 -0.1778)
						)
						(arc
							(start -0.2794 0.1778)
							(mid -0.249642 0.249642)
							(end -0.1778 0.2794)
						)
						(arc
							(start 0.1778 0.2794)
							(mid 0.249642 0.249642)
							(end 0.2794 0.1778)
						)
						(arc
							(start 0.2794 -0.1778)
							(mid 0.249642 -0.249642)
							(end 0.1778 -0.2794)
						)
					)
					(width 0)
					(fill yes)
				)
			)
		)
	)
	(footprint ""
		(layer "F.Cu")
		(at 16.874998 -46.649894 180)
		(property "Reference" "D24"
			(at 0 0 180)
			(layer "F.SilkS")
			(hide yes)
			(effects
				(font
					(size 1.27 1.27)
				)
			)
		)
		(property "Value" "RB551V30-GP"
			(at 0 -6.7818 180)
			(unlocked yes)
			(layer "F.Fab")
			(hide yes)
			(effects
				(font
					(size 1.016 1.016)
					(thickness 0.1524)
				)
			)
		)
		(property "Device Type" "SOD323AKH38"
			(at 0 -8.6868 180)
			(unlocked yes)
			(layer "F.Fab")
			(hide yes)
			(effects
				(font
					(size 1.016 1.016)
					(thickness 0.1524)
				)
			)
		)
		(duplicate_pad_numbers_are_jumpers no)
		(fp_line
			(start 0.889 2.159)
			(end -0.889 2.159)
			(stroke
				(width 0.1524)
				(type default)
			)
			(layer "F.SilkS")
		)
		(fp_line
			(start 0.889 -1.9304)
			(end 0.889 2.159)
			(stroke
				(width 0.1524)
				(type default)
			)
			(layer "F.SilkS")
		)
		(fp_line
			(start 0.762 2.0574)
			(end -0.762 2.0574)
			(stroke
				(width 0.508)
				(type default)
			)
			(layer "F.SilkS")
		)
		(fp_line
			(start -0.889 2.159)
			(end -0.889 -1.9304)
			(stroke
				(width 0.1524)
				(type default)
			)
			(layer "F.SilkS")
		)
		(fp_line
			(start -0.889 -1.9304)
			(end 0.889 -1.9304)
			(stroke
				(width 0.1524)
				(type default)
			)
			(layer "F.SilkS")
		)
		(fp_rect
			(start -1.016 2.3114)
			(end 1.016 -2.0066)
			(stroke
				(width 0)
				(type default)
			)
			(fill no)
			(layer "F.CrtYd")
		)
		(fp_poly
			(pts
				(xy -1.016 -2.0066) (xy 1.016 -2.0066) (xy 1.016 2.3114) (xy -1.016 2.3114)
			)
			(stroke
				(width 0)
				(type default)
			)
			(fill no)
			(layer "F.Fab")
		)
		(pad "A" smd rect
			(at 0 -1.143 180)
			(size 0.5588 1.016)
			(layers "F.Cu" "F.Mask" "F.Paste")
			(net "SW_HDD_R24")
		)
		(pad "K" smd rect
			(at 0 1.143 180)
			(size 0.5588 1.016)
			(layers "F.Cu" "F.Mask" "F.Paste")
			(net "SW_HDD_N24")
		)
	)
	(footprint ""
		(layer "F.Cu")
		(at 475.149926 -176.000918 -90)
		(property "Reference" "C340"
			(at 0 0 270)
			(layer "F.SilkS")
			(hide yes)
			(effects
				(font
					(size 1.27 1.27)
				)
			)
		)
		(property "Value" "SC10U16V6KX-2GP"
			(at -0.0762 -5.1308 270)
			(unlocked yes)
			(layer "F.Fab")
			(hide yes)
			(effects
				(font
					(size 1.016 1.016)
					(thickness 0.1524)
				)
			)
		)
		(property "Device Type" "C1206H71"
			(at -0.127 -6.6548 270)
			(unlocked yes)
			(layer "F.Fab")
			(hide yes)
			(effects
				(font
					(size 1.016 1.016)
					(thickness 0.1524)
				)
			)
		)
		(duplicate_pad_numbers_are_jumpers no)
		(fp_line
			(start -1.016 2.2352)
			(end -1.016 0.8382)
			(stroke
				(width 0.1524)
				(type default)
			)
			(layer "F.SilkS")
		)
		(fp_line
			(start 1.016 2.2352)
			(end -1.016 2.2352)
			(stroke
				(width 0.1524)
				(type default)
			)
			(layer "F.SilkS")
		)
		(fp_line
			(start 1.016 0.8382)
			(end 1.016 2.2352)
			(stroke
				(width 0.1524)
				(type default)
			)
			(layer "F.SilkS")
		)
		(fp_line
			(start -1.016 -0.8382)
			(end -1.016 -2.2352)
			(stroke
				(width 0.1524)
				(type default)
			)
			(layer "F.SilkS")
		)
		(fp_line
			(start -1.016 -2.2352)
			(end 1.016 -2.2352)
			(stroke
				(width 0.1524)
				(type default)
			)
			(layer "F.SilkS")
		)
		(fp_line
			(start 1.016 -2.2352)
			(end 1.016 -0.8382)
			(stroke
				(width 0.1524)
				(type default)
			)
			(layer "F.SilkS")
		)
		(fp_rect
			(start -1.0922 2.3114)
			(end 1.0922 -2.3114)
			(stroke
				(width 0)
				(type default)
			)
			(fill no)
			(layer "F.CrtYd")
		)
		(fp_poly
			(pts
				(xy 1.0922 -2.3114) (xy 1.0922 2.3114) (xy -1.0922 2.3114) (xy -1.0922 -2.3114)
			)
			(stroke
				(width 0)
				(type default)
			)
			(fill no)
			(layer "F.Fab")
		)
		(pad "1" smd rect
			(at 0 -1.397 270)
			(size 1.651 1.27)
			(layers "F.Cu" "F.Mask" "F.Paste")
			(net "P5V_HDD23")
		)
		(pad "2" smd rect
			(at 0 1.397 270)
			(size 1.651 1.27)
			(layers "F.Cu" "F.Mask" "F.Paste")
			(net "GND")
		)
	)
	(footprint ""
		(layer "F.Cu")
		(at 396.686786 -299.539914 -90)
		(property "Reference" "R317"
			(at 0 0 270)
			(layer "F.SilkS")
			(hide yes)
			(effects
				(font
					(size 1.27 1.27)
				)
			)
		)
		(property "Value" "2R6F-GP"
			(at -0.0508 -4.8514 270)
			(unlocked yes)
			(layer "F.Fab")
			(hide yes)
			(effects
				(font
					(size 1.016 1.016)
					(thickness 0.1524)
				)
			)
		)
		(property "Device Type" "R1206H26"
			(at 0 -6.3754 270)
			(unlocked yes)
			(layer "F.Fab")
			(hide yes)
			(effects
				(font
					(size 1.016 1.016)
					(thickness 0.1524)
				)
			)
		)
		(duplicate_pad_numbers_are_jumpers no)
		(fp_line
			(start -1.016 2.2352)
			(end -1.016 -2.2352)
			(stroke
				(width 0.1524)
				(type default)
			)
			(layer "F.SilkS")
		)
		(fp_line
			(start 1.016 2.2352)
			(end -1.016 2.2352)
			(stroke
				(width 0.1524)
				(type default)
			)
			(layer "F.SilkS")
		)
		(fp_line
			(start -1.016 -2.2352)
			(end 1.016 -2.2352)
			(stroke
				(width 0.1524)
				(type default)
			)
			(layer "F.SilkS")
		)
		(fp_line
			(start 1.016 -2.2352)
			(end 1.016 2.2352)
			(stroke
				(width 0.1524)
				(type default)
			)
			(layer "F.SilkS")
		)
		(fp_rect
			(start -1.0922 2.3114)
			(end 1.0922 -2.3114)
			(stroke
				(width 0)
				(type default)
			)
			(fill no)
			(layer "F.CrtYd")
		)
		(fp_poly
			(pts
				(xy -1.0922 -2.3114) (xy 1.0922 -2.3114) (xy 1.0922 2.3114) (xy -1.0922 2.3114)
			)
			(stroke
				(width 0)
				(type default)
			)
			(fill no)
			(layer "F.Fab")
		)
		(pad "1" smd rect
			(at 0 -1.397 270)
			(size 1.651 1.27)
			(layers "F.Cu" "F.Mask" "F.Paste")
			(net "P12V_HDD8")
		)
		(pad "2" smd rect
			(at 0 1.397 270)
			(size 1.651 1.27)
			(layers "F.Cu" "F.Mask" "F.Paste")
			(net "12V_PRE_8")
		)
	)
	(footprint ""
		(layer "F.Cu")
		(at 414.639252 -43.939968 90)
		(property "Reference" "VIA14"
			(at 0 0 90)
			(layer "F.SilkS")
			(hide yes)
			(effects
				(font
					(size 1.27 1.27)
				)
			)
		)
		(property "Value" "100OHM-8L-1D6MM-L18L16-GP"
			(at -3.7211 -4.5085 90)
			(unlocked yes)
			(layer "F.Fab")
			(hide yes)
			(effects
				(font
					(size 1.016 1.016)
					(thickness 0.1524)
				)
			)
		)
		(property "Device Type" "VIA-PCIE-4P-394076"
			(at -3.7211 -6.0325 90)
			(unlocked yes)
			(layer "F.Fab")
			(hide yes)
			(effects
				(font
					(size 1.016 1.016)
					(thickness 0.1524)
				)
			)
		)
		(duplicate_pad_numbers_are_jumpers no)
		(fp_rect
			(start -1.9685 0.381)
			(end 1.9685 -0.381)
			(stroke
				(width 0)
				(type default)
			)
			(fill no)
			(layer "F.CrtYd")
		)
		(fp_rect
			(start -1.9685 0.381)
			(end 1.9685 -0.381)
			(stroke
				(width 0)
				(type default)
			)
			(fill no)
			(layer "F.Fab")
		)
		(pad "1" thru_hole circle
			(at -1.5875 0 90)
			(size 0.508 0.508)
			(drill 0.254)
			(layers "*.Cu" "*.Mask")
			(remove_unused_layers no)
			(net "GND")
			(clearance 0.127)
			(thermal_gap 0.127)
		)
		(pad "2" thru_hole circle
			(at -0.5715 0 90)
			(size 0.508 0.508)
			(drill 0.254)
			(layers "*.Cu" "*.Mask")
			(remove_unused_layers no)
			(net "PHY_SCC_A_TO_DRV_A_33_DP")
			(clearance 0.127)
			(thermal_gap 0.127)
		)
		(pad "3" thru_hole circle
			(at 0.5715 0 90)
			(size 0.508 0.508)
			(drill 0.254)
			(layers "*.Cu" "*.Mask")
			(remove_unused_layers no)
			(net "PHY_SCC_A_TO_DRV_A_33_DN")
			(clearance 0.127)
			(thermal_gap 0.127)
		)
		(pad "4" thru_hole circle
			(at 1.5875 0 90)
			(size 0.508 0.508)
			(drill 0.254)
			(layers "*.Cu" "*.Mask")
			(remove_unused_layers no)
			(net "GND")
			(clearance 0.127)
			(thermal_gap 0.127)
		)
	)
	(footprint ""
		(layer "F.Cu")
		(at 469.942926 -54.523894 90)
		(property "Reference" "C504"
			(at 0 0 90)
			(layer "F.SilkS")
			(hide yes)
			(effects
				(font
					(size 1.27 1.27)
				)
			)
		)
		(property "Value" "SCD033U25V2KX-GP"
			(at 1.1811 -2.7051 90)
			(unlocked yes)
			(layer "F.Fab")
			(hide yes)
			(effects
				(font
					(size 1.016 1.016)
					(thickness 0.1524)
				)
			)
		)
		(property "Device Type" "C402H22"
			(at 1.1811 -4.2291 90)
			(unlocked yes)
			(layer "F.Fab")
			(hide yes)
			(effects
				(font
					(size 1.016 1.016)
					(thickness 0.1524)
				)
			)
		)
		(duplicate_pad_numbers_are_jumpers no)
		(fp_rect
			(start -0.4318 0.9525)
			(end 0.4318 -0.9525)
			(stroke
				(width 0)
				(type default)
			)
			(fill no)
			(layer "F.CrtYd")
		)
		(fp_rect
			(start -0.4318 0.9525)
			(end 0.4318 -0.9525)
			(stroke
				(width 0)
				(type default)
			)
			(fill no)
			(layer "F.Fab")
		)
		(pad "1" smd custom
			(at 0 -0.4445 90)
			(size 0.1524 0.1524)
			(layers "F.Cu" "F.Mask" "F.Paste")
			(net "P12V_A")
			(options
				(clearance outline)
				(anchor circle)
			)
			(primitives
				(gr_poly
					(pts
						(arc
							(start 0.3048 -0.2032)
							(mid 0.275042 -0.275042)
							(end 0.2032 -0.3048)
						)
						(arc
							(start -0.2032 -0.3048)
							(mid -0.275042 -0.275042)
							(end -0.3048 -0.2032)
						)
						(arc
							(start -0.3048 0.2032)
							(mid -0.275042 0.275042)
							(end -0.2032 0.3048)
						)
						(arc
							(start 0.2032 0.3048)
							(mid 0.275042 0.275042)
							(end 0.3048 0.2032)
						)
					)
					(width 0)
					(fill yes)
				)
			)
		)
		(pad "2" smd custom
			(at 0 0.4445 90)
			(size 0.1524 0.1524)
			(layers "F.Cu" "F.Mask" "F.Paste")
			(net "SW_HDD_N35")
			(options
				(clearance outline)
				(anchor circle)
			)
			(primitives
				(gr_poly
					(pts
						(arc
							(start 0.3048 -0.2032)
							(mid 0.275042 -0.275042)
							(end 0.2032 -0.3048)
						)
						(arc
							(start -0.2032 -0.3048)
							(mid -0.275042 -0.275042)
							(end -0.3048 -0.2032)
						)
						(arc
							(start -0.3048 0.2032)
							(mid -0.275042 0.275042)
							(end -0.2032 0.3048)
						)
						(arc
							(start 0.2032 0.3048)
							(mid 0.275042 0.275042)
							(end 0.3048 0.2032)
						)
					)
					(width 0)
					(fill yes)
				)
			)
		)
	)
	(footprint ""
		(layer "F.Cu")
		(at 7.347204 -169.549572 90)
		(property "Reference" "R145"
			(at 0 0 90)
			(layer "F.SilkS")
			(hide yes)
			(effects
				(font
					(size 1.27 1.27)
				)
			)
		)
		(property "Value" "4K7R2J-2-GP"
			(at 0.064008 -3.993896 90)
			(unlocked yes)
			(layer "F.Fab")
			(hide yes)
			(effects
				(font
					(size 1.016 1.016)
					(thickness 0.1524)
				)
			)
		)
		(property "Device Type" "R402H16"
			(at 0.064008 -5.517896 90)
			(unlocked yes)
			(layer "F.Fab")
			(hide yes)
			(effects
				(font
					(size 1.016 1.016)
					(thickness 0.1524)
				)
			)
		)
		(duplicate_pad_numbers_are_jumpers no)
		(fp_line
			(start 0.508 -0.9398)
			(end -0.508 -0.9398)
			(stroke
				(width 0.1524)
				(type default)
			)
			(layer "F.SilkS")
		)
		(fp_line
			(start -0.508 -0.9398)
			(end -0.508 0.9398)
			(stroke
				(width 0.1524)
				(type default)
			)
			(layer "F.SilkS")
		)
		(fp_rect
			(start -0.508 0.9398)
			(end 0.508 -0.9398)
			(stroke
				(width 0)
				(type default)
			)
			(fill no)
			(layer "F.CrtYd")
		)
		(fp_rect
			(start -0.508 0.9398)
			(end 0.508 -0.9398)
			(stroke
				(width 0)
				(type default)
			)
			(fill no)
			(layer "F.Fab")
		)
		(pad "1" smd custom
			(at 0 -0.4445 90)
			(size 0.1397 0.1397)
			(layers "F.Cu" "F.Mask" "F.Paste")
			(net "DRIVE_A_0_ACT")
			(options
				(clearance outline)
				(anchor circle)
			)
			(primitives
				(gr_poly
					(pts
						(arc
							(start -0.1778 -0.2794)
							(mid -0.249642 -0.249642)
							(end -0.2794 -0.1778)
						)
						(arc
							(start -0.2794 0.1778)
							(mid -0.249642 0.249642)
							(end -0.1778 0.2794)
						)
						(arc
							(start 0.1778 0.2794)
							(mid 0.249642 0.249642)
							(end 0.2794 0.1778)
						)
						(arc
							(start 0.2794 -0.1778)
							(mid 0.249642 -0.249642)
							(end 0.1778 -0.2794)
						)
					)
					(width 0)
					(fill yes)
				)
			)
		)
		(pad "2" smd custom
			(at 0 0.4445 90)
			(size 0.1397 0.1397)
			(layers "F.Cu" "F.Mask" "F.Paste")
			(net "GND")
			(options
				(clearance outline)
				(anchor circle)
			)
			(primitives
				(gr_poly
					(pts
						(arc
							(start -0.1778 -0.2794)
							(mid -0.249642 -0.249642)
							(end -0.2794 -0.1778)
						)
						(arc
							(start -0.2794 0.1778)
							(mid -0.249642 0.249642)
							(end -0.1778 0.2794)
						)
						(arc
							(start 0.1778 0.2794)
							(mid 0.249642 0.249642)
							(end 0.2794 0.1778)
						)
						(arc
							(start 0.2794 -0.1778)
							(mid 0.249642 -0.249642)
							(end 0.1778 -0.2794)
						)
					)
					(width 0)
					(fill yes)
				)
			)
		)
	)
)
